# BASEBOARD_FAB2 (Tioga Pass) — schematic netlist excerpt (pin names and nets, part order shuffled) for the footprints in the layout excerpt that follows; sources: Cadence DE-HDL packaged netlist, KiCad conversion of Wiwynn_Tioga_Pass_MB.brd

J9U1  SCONN288_H44441003  SCONN  pkg PIP  page 80
  \12v\(1)  = P12V_NVDIMM_GHJ
  VSS(93)  = GND
  DQ(4)  = M_H_DQ<4>
  VSS(92)  = GND
  DQ(0)  = M_H_DQ<0>
  VSS(91)  = GND
  DQS9P  = M_H_DQS_DP<9>
  DQS9N  = M_H_DQS_DN<9>
  VSS(90)  = GND
  DQ(6)  = M_H_DQ<6>
  VSS(89)  = GND
  DQ(2)  = M_H_DQ<2>
  VSS(88)  = GND
  DQ(12)  = M_H_DQ<12>
  VSS(87)  = GND
  DQ(8)  = M_H_DQ<8>
  VSS(86)  = GND
  DQS10P  = M_H_DQS_DP<10>
  DQS10N  = M_H_DQS_DN<10>
  VSS(85)  = GND
  DQ(14)  = M_H_DQ<14>
  VSS(84)  = GND
  DQ(10)  = M_H_DQ<10>
  VSS(83)  = GND
  DQ(20)  = M_H_DQ<20>
  VSS(82)  = GND
  DQ(16)  = M_H_DQ<16>
  VSS(81)  = GND
  DQS11P  = M_H_DQS_DP<11>
  DQS11N  = M_H_DQS_DN<11>
  VSS(80)  = GND
  DQ(22)  = M_H_DQ<22>
  VSS(79)  = GND
  DQ(18)  = M_H_DQ<18>
  VSS(78)  = GND
  DQ(28)  = M_H_DQ<28>
  VSS(77)  = GND
  DQ(24)  = M_H_DQ<24>
  VSS(76)  = GND
  DQS12P  = M_H_DQS_DP<12>
  DQS12N  = M_H_DQS_DN<12>
  VSS(75)  = GND
  DQ(30)  = M_H_DQ<30>
  VSS(74)  = GND
  DQ(26)  = M_H_DQ<26>
  VSS(73)  = GND
  CB(4)  = M_H_ECC<4>
  VSS(72)  = GND
  CB(0)  = M_H_ECC<0>
  VSS(71)  = GND
  DQS17P  = M_H_DQS_DP<17>
  DQS17N  = M_H_DQS_DN<17>
  VSS(70)  = GND
  CB(6)  = M_H_ECC<6>
  VSS(69)  = GND
  CB(2)  = M_H_ECC<2>
  VSS(68)  = GND
  RESET_N  = M_GHJ_RST_N
  VDD(25)  = PVDDQ_GHJ
  CKE(0)  = M_H_CKE<2>
  VDD(24)  = PVDDQ_GHJ
  ACT_N  = M_H_ACT_N
  BG(0)  = M_H_BG<0>
  VDD(23)  = PVDDQ_GHJ
  A12  = M_H_MA<12>
  A9  = M_H_MA<9>
  VDD(22)  = PVDDQ_GHJ
  A8  = M_H_MA<8>
  A6  = M_H_MA<6>
  VDD(21)  = PVDDQ_GHJ
  A3  = M_H_MA<3>
  A1  = M_H_MA<1>
  VDD(20)  = PVDDQ_GHJ
  CK0P  = M_H_CLK_DP<2>
  CK0N  = M_H_CLK_DN<2>
  VDD(19)  = PVDDQ_GHJ
  VTT(1)  = PVTT_GHJ
  EVENT_N  = FM_DIMM_EVENT_COD_N
  A0  = M_H_MA<0>
  VDD(18)  = PVDDQ_GHJ
  BA(0)  = M_H_BA<0>
  A16_RAS_N  = M_H_MA<16>
  VDD(17)  = PVDDQ_GHJ
  S0_N  = M_H_CS_N<4>
  VDD(16)  = PVDDQ_GHJ
  A15_CAS_N  = M_H_MA<15>
  ODT(0)  = M_H_ODT<2>
  VDD(15)  = PVDDQ_GHJ
  S1_N  = M_H_CS_N<5>
  VDD(14)  = PVDDQ_GHJ
  ODT(1)  = M_H_ODT<3>
  VDD(13)  = PVDDQ_GHJ
  S2_N_C(0)  = M_H_CS_N<6>
  VSS(67)  = GND
  DQ(36)  = M_H_DQ<36>
  VSS(66)  = GND
  DQ(32)  = M_H_DQ<32>
  VSS(65)  = GND
  DQS13P  = M_H_DQS_DP<13>
  DQS13N  = M_H_DQS_DN<13>
  VSS(64)  = GND
  DQ(38)  = M_H_DQ<38>
  VSS(63)  = GND
  DQ(34)  = M_H_DQ<34>
  VSS(62)  = GND
  DQ(44)  = M_H_DQ<44>
  VSS(61)  = GND
  DQ(40)  = M_H_DQ<40>
  VSS(60)  = GND
  DQS14P  = M_H_DQS_DP<14>
  DQS14N  = M_H_DQS_DN<14>
  VSS(59)  = GND
  DQ(46)  = M_H_DQ<46>
  VSS(58)  = GND
  DQ(42)  = M_H_DQ<42>
  VSS(57)  = GND
  DQ(52)  = M_H_DQ<52>
  VSS(56)  = GND
  DQ(48)  = M_H_DQ<48>
  VSS(55)  = GND
  DQS15P  = M_H_DQS_DP<15>
  DQS15N  = M_H_DQS_DN<15>
  VSS(54)  = GND
  DQ(54)  = M_H_DQ<54>
  VSS(53)  = GND
  DQ(50)  = M_H_DQ<50>
  VSS(52)  = GND
  DQ(60)  = M_H_DQ<60>
  VSS(51)  = GND
  DQ(56)  = M_H_DQ<56>
  VSS(50)  = GND
  DQS16P  = M_H_DQS_DP<16>
  DQS16N  = M_H_DQS_DN<16>
  VSS(49)  = GND
  DQ(62)  = M_H_DQ<62>
  VSS(48)  = GND
  DQ(58)  = M_H_DQ<58>
  VSS(47)  = GND
  SA(0)  = PVPP_GHJ
  SA(1)  = PVPP_GHJ
  SCL  = SMB_DDR_GHJ_VPP_SCL
  VPP(4)  = PVPP_GHJ
  VPP(3)  = PVPP_GHJ
  RFU(2)  = TP_CH_H_DIMM0_RFU_2
  \12v\(0)  = P12V_NVDIMM_GHJ
  VREFCA  = M_H_VREF
  VSS(46)  = GND
  DQ(5)  = M_H_DQ<5>
  VSS(45)  = GND
  DQ(1)  = M_H_DQ<1>
  VSS(44)  = GND
  DQS0N  = M_H_DQS_DN<0>
  DQS0P  = M_H_DQS_DP<0>
  VSS(43)  = GND
  DQ(7)  = M_H_DQ<7>
  VSS(42)  = GND
  DQ(3)  = M_H_DQ<3>
  VSS(41)  = GND
  DQ(13)  = M_H_DQ<13>
  VSS(40)  = GND
  DQ(9)  = M_H_DQ<9>
  VSS(39)  = GND
  DQS1N  = M_H_DQS_DN<1>
  DQS1P  = M_H_DQS_DP<1>
  VSS(38)  = GND
  DQ(15)  = M_H_DQ<15>
  VSS(37)  = GND
  DQ(11)  = M_H_DQ<11>
  VSS(36)  = GND
  DQ(21)  = M_H_DQ<21>
  VSS(35)  = GND
  DQ(17)  = M_H_DQ<17>
  VSS(34)  = GND
  DQS2N  = M_H_DQS_DN<2>
  DQS2P  = M_H_DQS_DP<2>
  VSS(33)  = GND
  DQ(23)  = M_H_DQ<23>
  VSS(32)  = GND
  DQ(19)  = M_H_DQ<19>
  VSS(31)  = GND
  DQ(29)  = M_H_DQ<29>
  VSS(30)  = GND
  DQ(25)  = M_H_DQ<25>
  VSS(29)  = GND
  DQS3N  = M_H_DQS_DN<3>
  DQS3P  = M_H_DQS_DP<3>
  VSS(28)  = GND
  DQ(31)  = M_H_DQ<31>
  VSS(27)  = GND
  DQ(27)  = M_H_DQ<27>
  VSS(26)  = GND
  CB(5)  = M_H_ECC<5>
  VSS(25)  = GND
  CB(1)  = M_H_ECC<1>
  VSS(24)  = GND
  DQS8N  = M_H_DQS_DN<8>
  DQS8P  = M_H_DQS_DP<8>
  VSS(23)  = GND
  CB(7)  = M_H_ECC<7>
  VSS(22)  = GND
  CB(3)  = M_H_ECC<3>
  VSS(21)  = GND
  CKE(1)  = M_H_CKE<3>
  VDD(12)  = PVDDQ_GHJ
  RFU(0)  = TP_CH_H_DIMM0_RFU_0
  VDD(11)  = PVDDQ_GHJ
  BG(1)  = M_H_BG<1>
  ALERT_N  = M_H_ALERT_N
  VDD(10)  = PVDDQ_GHJ
  A11  = M_H_MA<11>
  A7  = M_H_MA<7>
  VDD(9)  = PVDDQ_GHJ
  A5  = M_H_MA<5>
  A4  = M_H_MA<4>
  VDD(8)  = PVDDQ_GHJ
  A2  = M_H_MA<2>
  VDD(7)  = PVDDQ_GHJ
  CK1P  = M_H_CLK_DP<3>
  CK1N  = M_H_CLK_DN<3>
  VDD(6)  = PVDDQ_GHJ
  VTT(0)  = PVTT_GHJ
  PAR  = M_H_PAR
  VDD(5)  = PVDDQ_GHJ
  BA(1)  = M_H_BA<1>
  A10  = M_H_MA<10>
  VDD(4)  = PVDDQ_GHJ
  RFU(1)  = TP_CH_H_DIMM0_RFU_1
  A14_WE_N  = M_H_MA<14>
  VDD(3)  = PVDDQ_GHJ
  SAVE_N_NC  = FM_ADR_COMPLETE_GHJ_N
  VDD(2)  = PVDDQ_GHJ
  A13  = M_H_MA<13>
  VDD(1)  = PVDDQ_GHJ
  A17  = M_H_MA<17>
  C(2)  = M_H_C<2>
  VDD(0)  = PVDDQ_GHJ
  S3_N_C(1)  = M_H_CS_N<7>
  SA(2)  = GND
  VSS(20)  = GND
  DQ(37)  = M_H_DQ<37>
  VSS(19)  = GND
  DQ(33)  = M_H_DQ<33>
  VSS(18)  = GND
  DQS4N  = M_H_DQS_DN<4>
  DQS4P  = M_H_DQS_DP<4>
  VSS(17)  = GND
  DQ(39)  = M_H_DQ<39>
  VSS(16)  = GND
  DQ(35)  = M_H_DQ<35>
  VSS(15)  = GND
  DQ(45)  = M_H_DQ<45>
  VSS(14)  = GND
  DQ(41)  = M_H_DQ<41>
  VSS(13)  = GND
  DQS5N  = M_H_DQS_DN<5>
  DQS5P  = M_H_DQS_DP<5>
  VSS(12)  = GND
  DQ(47)  = M_H_DQ<47>
  VSS(11)  = GND
  DQ(43)  = M_H_DQ<43>
  VSS(10)  = GND
  DQ(53)  = M_H_DQ<53>
  VSS(9)  = GND
  DQ(49)  = M_H_DQ<49>
  VSS(8)  = GND
  DQS6N  = M_H_DQS_DN<6>
  DQS6P  = M_H_DQS_DP<6>
  VSS(7)  = GND
  DQ(55)  = M_H_DQ<55>
  VSS(6)  = GND
  DQ(51)  = M_H_DQ<51>
  VSS(5)  = GND
  DQ(61)  = M_H_DQ<61>
  VSS(4)  = GND
  DQ(57)  = M_H_DQ<57>
  VSS(3)  = GND
  DQS7N  = M_H_DQS_DN<7>
  DQS7P  = M_H_DQS_DP<7>
  VSS(2)  = GND
  DQ(63)  = M_H_DQ<63>
  VSS(1)  = GND
  DQ(59)  = M_H_DQ<59>
  VSS(0)  = GND
  VDDSPD  = PVPP_GHJ
  SDA  = SMB_DDR_GHJ_VPP_SDA
  VPP(1)  = PVPP_GHJ
  VPP(0)  = PVPP_GHJ
  VPP(2)  = PVPP_GHJ

(kicad_pcb
	(version 20260206)
	(generator "pcbnew")
	(generator_version "10.0")
	(general
		(thickness 1.6)
		(legacy_teardrops no)
	)
	(paper "A4")
	(title_block
		(title "Wiwynn_Tioga_Pass_MB.brd")
		(comment 1 "Tioga Pass / footprint 3114 of 4770 (J9U1), pads 202-249 of 291")
	)
	(layers
		(0 "F.Cu" signal "TOP")
		(4 "In1.Cu" signal "L2GND")
		(6 "In2.Cu" signal "L3")
		(8 "In3.Cu" signal "L4GND")
		(10 "In4.Cu" signal "L5")
		(12 "In5.Cu" signal "L6GND")
		(14 "In6.Cu" signal "L7VCC")
		(16 "In7.Cu" signal "L8VCC")
		(18 "In8.Cu" signal "L9GND")
		(20 "In9.Cu" signal "L10")
		(22 "In10.Cu" signal "L11GND")
		(24 "In11.Cu" signal "L12")
		(26 "In12.Cu" signal "L13GND")
		(2 "B.Cu" signal "BOTTOM")
		(9 "F.Adhes" user "F.Adhesive")
		(11 "B.Adhes" user "B.Adhesive")
		(13 "F.Paste" user "Package Geometry/Pastemask Top")
		(15 "B.Paste" user "Package Geometry/Pastemask Bottom")
		(5 "F.SilkS" user "Ref Des/Silkscreen Top")
		(7 "B.SilkS" user "Ref Des/Silkscreen Bottom")
		(1 "F.Mask" user "Board Geometry/Soldermask Top")
		(3 "B.Mask" user "Board Geometry/Soldermask Bottom")
		(17 "Dwgs.User" user "User.Drawings")
		(19 "Cmts.User" user "User.Comments")
		(21 "Eco1.User" user "User.Eco1")
		(23 "Eco2.User" user "User.Eco2")
		(25 "Edge.Cuts" user "Board Geometry/Outline")
		(27 "Margin" user)
		(31 "F.CrtYd" user "Package Geometry/Place Bound Top")
		(29 "B.CrtYd" user "Package Geometry/Place Bound Bottom")
		(35 "F.Fab" user "Ref Des/Assembly Top")
		(33 "B.Fab" user "Ref Des/Assembly Bottom")
	)
	(footprint ""
		(layer "B.Cu")
		(at 29.699458 -15.222982 90)
		(property "Reference" "J9U1"
			(at 2.276348 37.991542 0)
			(unlocked yes)
			(layer "B.SilkS")
			(effects
				(font
					(size 0.7874 0.5842)
					(thickness 0.1524)
				)
				(justify left mirror)
			)
		)
		(property "Value" ""
			(at 0 0 90)
			(layer "B.Fab")
			(effects
				(font
					(size 1.27 1.27)
				)
				(justify mirror)
			)
		)
		(duplicate_pad_numbers_are_jumpers no)
		(pad "199" smd rect
			(at -4.59994 45.900086 270)
			(size 1.8034 0.508)
			(layers "B.Cu" "B.Mask" "B.Paste")
			(net "M_H_ECC<7>")
		)
		(pad "200" smd rect
			(at -4.59994 46.74997 270)
			(size 1.8034 0.508)
			(layers "B.Cu" "B.Mask" "B.Paste")
			(net "GND")
		)
		(pad "201" smd rect
			(at -4.59994 47.600108 270)
			(size 1.8034 0.508)
			(layers "B.Cu" "B.Mask" "B.Paste")
			(net "M_H_ECC<3>")
		)
		(pad "202" smd rect
			(at -4.59994 48.449992 270)
			(size 1.8034 0.508)
			(layers "B.Cu" "B.Mask" "B.Paste")
			(net "GND")
		)
		(pad "203" smd rect
			(at -4.59994 49.299876 270)
			(size 1.8034 0.508)
			(layers "B.Cu" "B.Mask" "B.Paste")
			(net "M_H_CKE<3>")
		)
		(pad "204" smd rect
			(at -4.59994 50.150014 270)
			(size 1.8034 0.508)
			(layers "B.Cu" "B.Mask" "B.Paste")
			(net "PVDDQ_GHJ")
		)
		(pad "205" smd rect
			(at -4.59994 50.999898 270)
			(size 1.8034 0.508)
			(layers "B.Cu" "B.Mask" "B.Paste")
			(net "TP_CH_H_DIMM0_RFU_0")
		)
		(pad "206" smd rect
			(at -4.59994 51.850036 270)
			(size 1.8034 0.508)
			(layers "B.Cu" "B.Mask" "B.Paste")
			(net "PVDDQ_GHJ")
		)
		(pad "207" smd rect
			(at -4.59994 52.69992 270)
			(size 1.8034 0.508)
			(layers "B.Cu" "B.Mask" "B.Paste")
			(net "M_H_BG<1>")
		)
		(pad "208" smd rect
			(at -4.59994 53.550058 270)
			(size 1.8034 0.508)
			(layers "B.Cu" "B.Mask" "B.Paste")
			(net "M_H_ALERT_N")
		)
		(pad "209" smd rect
			(at -4.59994 54.399942 270)
			(size 1.8034 0.508)
			(layers "B.Cu" "B.Mask" "B.Paste")
			(net "PVDDQ_GHJ")
		)
		(pad "210" smd rect
			(at -4.59994 55.25008 270)
			(size 1.8034 0.508)
			(layers "B.Cu" "B.Mask" "B.Paste")
			(net "M_H_MA<11>")
		)
		(pad "211" smd rect
			(at -4.59994 56.099964 270)
			(size 1.8034 0.508)
			(layers "B.Cu" "B.Mask" "B.Paste")
			(net "M_H_MA<7>")
		)
		(pad "212" smd rect
			(at -4.59994 56.950102 270)
			(size 1.8034 0.508)
			(layers "B.Cu" "B.Mask" "B.Paste")
			(net "PVDDQ_GHJ")
		)
		(pad "213" smd rect
			(at -4.59994 57.799986 270)
			(size 1.8034 0.508)
			(layers "B.Cu" "B.Mask" "B.Paste")
			(net "M_H_MA<5>")
		)
		(pad "214" smd rect
			(at -4.59994 58.650124 270)
			(size 1.8034 0.508)
			(layers "B.Cu" "B.Mask" "B.Paste")
			(net "M_H_MA<4>")
		)
		(pad "215" smd rect
			(at -4.59994 59.500008 270)
			(size 1.8034 0.508)
			(layers "B.Cu" "B.Mask" "B.Paste")
			(net "PVDDQ_GHJ")
		)
		(pad "216" smd rect
			(at -4.59994 60.349892 270)
			(size 1.8034 0.508)
			(layers "B.Cu" "B.Mask" "B.Paste")
			(net "M_H_MA<2>")
		)
		(pad "217" smd rect
			(at -4.59994 61.20003 270)
			(size 1.8034 0.508)
			(layers "B.Cu" "B.Mask" "B.Paste")
			(net "PVDDQ_GHJ")
		)
		(pad "218" smd rect
			(at -4.59994 62.049914 270)
			(size 1.8034 0.508)
			(layers "B.Cu" "B.Mask" "B.Paste")
			(net "M_H_CLK_DP<3>")
		)
		(pad "219" smd rect
			(at -4.59994 62.900052 270)
			(size 1.8034 0.508)
			(layers "B.Cu" "B.Mask" "B.Paste")
			(net "M_H_CLK_DN<3>")
		)
		(pad "220" smd rect
			(at -4.59994 63.749936 270)
			(size 1.8034 0.508)
			(layers "B.Cu" "B.Mask" "B.Paste")
			(net "PVDDQ_GHJ")
		)
		(pad "221" smd rect
			(at -4.59994 64.600074 270)
			(size 1.8034 0.508)
			(layers "B.Cu" "B.Mask" "B.Paste")
			(net "PVTT_GHJ")
		)
		(pad "222" smd rect
			(at -4.59994 70.550024 270)
			(size 1.8034 0.508)
			(layers "B.Cu" "B.Mask" "B.Paste")
			(net "M_H_PAR")
		)
		(pad "223" smd rect
			(at -4.59994 71.399908 270)
			(size 1.8034 0.508)
			(layers "B.Cu" "B.Mask" "B.Paste")
			(net "PVDDQ_GHJ")
		)
		(pad "224" smd rect
			(at -4.59994 72.250046 270)
			(size 1.8034 0.508)
			(layers "B.Cu" "B.Mask" "B.Paste")
			(net "M_H_BA<1>")
		)
		(pad "225" smd rect
			(at -4.59994 73.09993 270)
			(size 1.8034 0.508)
			(layers "B.Cu" "B.Mask" "B.Paste")
			(net "M_H_MA<10>")
		)
		(pad "226" smd rect
			(at -4.59994 73.950068 270)
			(size 1.8034 0.508)
			(layers "B.Cu" "B.Mask" "B.Paste")
			(net "PVDDQ_GHJ")
		)
		(pad "227" smd rect
			(at -4.59994 74.799952 270)
			(size 1.8034 0.508)
			(layers "B.Cu" "B.Mask" "B.Paste")
			(net "TP_CH_H_DIMM0_RFU_1")
		)
		(pad "228" smd rect
			(at -4.59994 75.65009 270)
			(size 1.8034 0.508)
			(layers "B.Cu" "B.Mask" "B.Paste")
			(net "M_H_MA<14>")
		)
		(pad "229" smd rect
			(at -4.59994 76.499974 270)
			(size 1.8034 0.508)
			(layers "B.Cu" "B.Mask" "B.Paste")
			(net "PVDDQ_GHJ")
		)
		(pad "230" smd rect
			(at -4.59994 77.350112 270)
			(size 1.8034 0.508)
			(layers "B.Cu" "B.Mask" "B.Paste")
			(net "FM_ADR_COMPLETE_GHJ_N")
		)
		(pad "231" smd rect
			(at -4.59994 78.199996 270)
			(size 1.8034 0.508)
			(layers "B.Cu" "B.Mask" "B.Paste")
			(net "PVDDQ_GHJ")
		)
		(pad "232" smd rect
			(at -4.59994 79.04988 270)
			(size 1.8034 0.508)
			(layers "B.Cu" "B.Mask" "B.Paste")
			(net "M_H_MA<13>")
		)
		(pad "233" smd rect
			(at -4.59994 79.900018 270)
			(size 1.8034 0.508)
			(layers "B.Cu" "B.Mask" "B.Paste")
			(net "PVDDQ_GHJ")
		)
		(pad "234" smd rect
			(at -4.59994 80.749902 270)
			(size 1.8034 0.508)
			(layers "B.Cu" "B.Mask" "B.Paste")
			(net "M_H_MA<17>")
		)
		(pad "235" smd rect
			(at -4.59994 81.60004 270)
			(size 1.8034 0.508)
			(layers "B.Cu" "B.Mask" "B.Paste")
			(net "M_H_C<2>")
		)
		(pad "236" smd rect
			(at -4.59994 82.449924 270)
			(size 1.8034 0.508)
			(layers "B.Cu" "B.Mask" "B.Paste")
			(net "PVDDQ_GHJ")
		)
		(pad "237" smd rect
			(at -4.59994 83.300062 270)
			(size 1.8034 0.508)
			(layers "B.Cu" "B.Mask" "B.Paste")
			(net "M_H_CS_N<7>")
		)
		(pad "238" smd rect
			(at -4.59994 84.149946 270)
			(size 1.8034 0.508)
			(layers "B.Cu" "B.Mask" "B.Paste")
			(net "GND")
		)
		(pad "239" smd rect
			(at -4.59994 85.000084 270)
			(size 1.8034 0.508)
			(layers "B.Cu" "B.Mask" "B.Paste")
			(net "GND")
		)
		(pad "240" smd rect
			(at -4.59994 85.849968 270)
			(size 1.8034 0.508)
			(layers "B.Cu" "B.Mask" "B.Paste")
			(net "M_H_DQ<37>")
		)
		(pad "241" smd rect
			(at -4.59994 86.700106 270)
			(size 1.8034 0.508)
			(layers "B.Cu" "B.Mask" "B.Paste")
			(net "GND")
		)
		(pad "242" smd rect
			(at -4.59994 87.54999 270)
			(size 1.8034 0.508)
			(layers "B.Cu" "B.Mask" "B.Paste")
			(net "M_H_DQ<33>")
		)
		(pad "243" smd rect
			(at -4.59994 88.399874 270)
			(size 1.8034 0.508)
			(layers "B.Cu" "B.Mask" "B.Paste")
			(net "GND")
		)
		(pad "244" smd rect
			(at -4.59994 89.250012 270)
			(size 1.8034 0.508)
			(layers "B.Cu" "B.Mask" "B.Paste")
			(net "M_H_DQS_DN<4>")
		)
		(pad "245" smd rect
			(at -4.59994 90.099896 270)
			(size 1.8034 0.508)
			(layers "B.Cu" "B.Mask" "B.Paste")
			(net "M_H_DQS_DP<4>")
		)
		(pad "246" smd rect
			(at -4.59994 90.950034 270)
			(size 1.8034 0.508)
			(layers "B.Cu" "B.Mask" "B.Paste")
			(net "GND")
		)
	)
)
